(kicad_pcb
	(version 20260206)
	(generator "pcbnew")
	(generator_version "10.0")
	(general
		(thickness 1.6)
		(legacy_teardrops no)
	)
	(paper "A4")
	(title_block
		(title "04192023_DAF0TMB3IC0_F0TG_MB_C_brd_V02_OCP.brd")
		(comment 1 "Grand Teton / footprints 6640-6647 of 8354")
	)
	(layers
		(0 "F.Cu" signal "TOP")
		(4 "In1.Cu" signal "GND")
		(6 "In2.Cu" signal "IN1")
		(8 "In3.Cu" signal "GND1")
		(10 "In4.Cu" signal "IN2")
		(12 "In5.Cu" signal "GND2")
		(14 "In6.Cu" signal "IN3")
		(16 "In7.Cu" signal "GND3")
		(18 "In8.Cu" signal "VCC")
		(20 "In9.Cu" signal "VCC1")
		(22 "In10.Cu" signal "GND4")
		(24 "In11.Cu" signal "IN4")
		(26 "In12.Cu" signal "GND5")
		(28 "In13.Cu" signal "IN5")
		(30 "In14.Cu" signal "GND6")
		(32 "In15.Cu" signal "IN6")
		(34 "In16.Cu" signal "GND7")
		(2 "B.Cu" signal "BOTTOM")
		(9 "F.Adhes" user "F.Adhesive")
		(11 "B.Adhes" user "B.Adhesive")
		(13 "F.Paste" user "Package Geometry/Pastemask Top")
		(15 "B.Paste" user "Package Geometry/Pastemask Bottom")
		(5 "F.SilkS" user "Ref Des/Silkscreen Top")
		(7 "B.SilkS" user "Ref Des/Silkscreen Bottom")
		(1 "F.Mask" user "Board Geometry/Soldermask Top")
		(3 "B.Mask" user "Board Geometry/Soldermask Bottom")
		(17 "Dwgs.User" user "User.Drawings")
		(19 "Cmts.User" user "User.Comments")
		(21 "Eco1.User" user "User.Eco1")
		(23 "Eco2.User" user "User.Eco2")
		(25 "Edge.Cuts" user "Board Geometry/Outline")
		(27 "Margin" user)
		(31 "F.CrtYd" user "Package Geometry/Place Bound Top")
		(29 "B.CrtYd" user "Package Geometry/Place Bound Bottom")
		(35 "F.Fab" user "Ref Des/Assembly Top")
		(33 "B.Fab" user "Ref Des/Assembly Bottom")
	)
	(footprint ""
		(layer "B.Cu")
		(at 32.552386 -190.948564 180)
		(property "Reference" "R306"
			(at 0 0 0)
			(layer "B.SilkS")
			(hide yes)
			(effects
				(font
					(size 1.27 1.27)
				)
				(justify mirror)
			)
		)
		(property "Value" ""
			(at 0 0 0)
			(layer "B.Fab")
			(effects
				(font
					(size 1.27 1.27)
				)
				(justify mirror)
			)
		)
		(duplicate_pad_numbers_are_jumpers no)
		(fp_line
			(start 0.7874 0.4064)
			(end 0.7874 -0.4064)
			(stroke
				(width 0.1524)
				(type default)
			)
			(layer "B.SilkS")
		)
		(fp_line
			(start 0.7874 -0.4064)
			(end -0.7874 -0.4064)
			(stroke
				(width 0.1524)
				(type default)
			)
			(layer "B.SilkS")
		)
		(fp_line
			(start -0.7874 0.4064)
			(end 0.7874 0.4064)
			(stroke
				(width 0.1524)
				(type default)
			)
			(layer "B.SilkS")
		)
		(fp_line
			(start -0.7874 -0.4064)
			(end -0.7874 0.4064)
			(stroke
				(width 0.1524)
				(type default)
			)
			(layer "B.SilkS")
		)
		(fp_line
			(start 0.67945 0.3048)
			(end 0.67945 -0.305054)
			(stroke
				(width 0.1)
				(type default)
			)
			(layer "B.Fab")
		)
		(fp_line
			(start 0.67945 -0.305054)
			(end 0.12065 -0.305054)
			(stroke
				(width 0.1)
				(type default)
			)
			(layer "B.Fab")
		)
		(fp_line
			(start 0.12065 0.3048)
			(end 0.67945 0.3048)
			(stroke
				(width 0.1)
				(type default)
			)
			(layer "B.Fab")
		)
		(fp_line
			(start 0.12065 0.2794)
			(end 0.12065 0.3048)
			(stroke
				(width 0.1)
				(type default)
			)
			(layer "B.Fab")
		)
		(fp_line
			(start 0.12065 -0.2794)
			(end -0.12065 -0.2794)
			(stroke
				(width 0.1)
				(type default)
			)
			(layer "B.Fab")
		)
		(fp_line
			(start 0.12065 -0.305054)
			(end 0.12065 -0.2794)
			(stroke
				(width 0.1)
				(type default)
			)
			(layer "B.Fab")
		)
		(fp_line
			(start -0.120396 0.3048)
			(end -0.120396 0.2794)
			(stroke
				(width 0.1)
				(type default)
			)
			(layer "B.Fab")
		)
		(fp_line
			(start -0.120396 0.2794)
			(end 0.12065 0.2794)
			(stroke
				(width 0.1)
				(type default)
			)
			(layer "B.Fab")
		)
		(fp_line
			(start -0.12065 -0.2794)
			(end -0.12065 -0.3048)
			(stroke
				(width 0.1)
				(type default)
			)
			(layer "B.Fab")
		)
		(fp_line
			(start -0.12065 -0.3048)
			(end -0.67945 -0.3048)
			(stroke
				(width 0.1)
				(type default)
			)
			(layer "B.Fab")
		)
		(fp_line
			(start -0.67945 0.3048)
			(end -0.120396 0.3048)
			(stroke
				(width 0.1)
				(type default)
			)
			(layer "B.Fab")
		)
		(fp_line
			(start -0.67945 -0.3048)
			(end -0.67945 0.3048)
			(stroke
				(width 0.1)
				(type default)
			)
			(layer "B.Fab")
		)
		(pad "1" smd circle
			(at 0.40005 0)
			(size 0 0)
			(layers "B.Cu" "B.Mask" "B.Paste")
			(net "PWRGD_CHD_CPU1_DIMM")
		)
		(pad "2" smd circle
			(at -0.40005 0)
			(size 0 0)
			(layers "B.Cu" "B.Mask" "B.Paste")
			(net "PWRGD_CHAF_CPU1")
		)
	)
	(footprint ""
		(layer "B.Cu")
		(at 72.689974 -173.870112 90)
		(property "Reference" "PC313_5"
			(at 0 0 90)
			(layer "B.SilkS")
			(hide yes)
			(effects
				(font
					(size 1.27 1.27)
				)
				(justify mirror)
			)
		)
		(property "Value" ""
			(at 0 0 90)
			(layer "B.Fab")
			(effects
				(font
					(size 1.27 1.27)
				)
				(justify mirror)
			)
		)
		(duplicate_pad_numbers_are_jumpers no)
		(fp_line
			(start 1.524 -0.762)
			(end -1.524 -0.762)
			(stroke
				(width 0.1524)
				(type default)
			)
			(layer "B.SilkS")
		)
		(fp_line
			(start -1.524 -0.762)
			(end -1.524 0.762)
			(stroke
				(width 0.1524)
				(type default)
			)
			(layer "B.SilkS")
		)
		(fp_line
			(start 1.524 0.762)
			(end 1.524 -0.762)
			(stroke
				(width 0.1524)
				(type default)
			)
			(layer "B.SilkS")
		)
		(fp_line
			(start -1.524 0.762)
			(end 1.524 0.762)
			(stroke
				(width 0.1524)
				(type default)
			)
			(layer "B.SilkS")
		)
		(fp_line
			(start 1.1049 -0.724916)
			(end 1.1049 0.724916)
			(stroke
				(width 0.1)
				(type default)
			)
			(layer "B.Fab")
		)
		(fp_line
			(start -1.1049 -0.724916)
			(end 1.1049 -0.724916)
			(stroke
				(width 0.1)
				(type default)
			)
			(layer "B.Fab")
		)
		(fp_line
			(start 1.1049 0.724916)
			(end -1.1049 0.724916)
			(stroke
				(width 0.1)
				(type default)
			)
			(layer "B.Fab")
		)
		(fp_line
			(start -1.1049 0.724916)
			(end -1.1049 -0.724916)
			(stroke
				(width 0.1)
				(type default)
			)
			(layer "B.Fab")
		)
		(pad "1" smd rect
			(at 0.889 0 90)
			(size 1.016 1.27)
			(layers "B.Cu" "B.Mask" "B.Paste")
			(net "SW_P12V_AUX_PVDDCR_CPU0_P1_FLT")
		)
		(pad "2" smd rect
			(at -0.889 0 90)
			(size 1.016 1.27)
			(layers "B.Cu" "B.Mask" "B.Paste")
			(net "GND")
		)
	)
	(footprint ""
		(layer "B.Cu")
		(at 180.281834 -421.37711 90)
		(property "Reference" "C9003"
			(at 0 0 90)
			(layer "B.SilkS")
			(hide yes)
			(effects
				(font
					(size 1.27 1.27)
				)
				(justify mirror)
			)
		)
		(property "Value" ""
			(at 0 0 90)
			(layer "B.Fab")
			(effects
				(font
					(size 1.27 1.27)
				)
				(justify mirror)
			)
		)
		(duplicate_pad_numbers_are_jumpers no)
		(fp_line
			(start 0.7874 -0.4064)
			(end -0.7874 -0.4064)
			(stroke
				(width 0.1524)
				(type default)
			)
			(layer "B.SilkS")
		)
		(fp_line
			(start -0.7874 -0.4064)
			(end -0.7874 0.4064)
			(stroke
				(width 0.1524)
				(type default)
			)
			(layer "B.SilkS")
		)
		(fp_line
			(start 0.7874 0.4064)
			(end 0.7874 -0.4064)
			(stroke
				(width 0.1524)
				(type default)
			)
			(layer "B.SilkS")
		)
		(fp_line
			(start -0.7874 0.4064)
			(end 0.7874 0.4064)
			(stroke
				(width 0.1524)
				(type default)
			)
			(layer "B.SilkS")
		)
		(fp_line
			(start 0.67945 -0.305054)
			(end 0.12065 -0.305054)
			(stroke
				(width 0.1)
				(type default)
			)
			(layer "B.Fab")
		)
		(fp_line
			(start 0.12065 -0.305054)
			(end 0.12065 -0.2794)
			(stroke
				(width 0.1)
				(type default)
			)
			(layer "B.Fab")
		)
		(fp_line
			(start -0.12065 -0.3048)
			(end -0.67945 -0.3048)
			(stroke
				(width 0.1)
				(type default)
			)
			(layer "B.Fab")
		)
		(fp_line
			(start -0.67945 -0.3048)
			(end -0.67945 0.3048)
			(stroke
				(width 0.1)
				(type default)
			)
			(layer "B.Fab")
		)
		(fp_line
			(start 0.12065 -0.2794)
			(end -0.12065 -0.2794)
			(stroke
				(width 0.1)
				(type default)
			)
			(layer "B.Fab")
		)
		(fp_line
			(start -0.12065 -0.2794)
			(end -0.12065 -0.3048)
			(stroke
				(width 0.1)
				(type default)
			)
			(layer "B.Fab")
		)
		(fp_line
			(start 0.12065 0.2794)
			(end 0.12065 0.3048)
			(stroke
				(width 0.1)
				(type default)
			)
			(layer "B.Fab")
		)
		(fp_line
			(start -0.120396 0.2794)
			(end 0.12065 0.2794)
			(stroke
				(width 0.1)
				(type default)
			)
			(layer "B.Fab")
		)
		(fp_line
			(start 0.67945 0.3048)
			(end 0.67945 -0.305054)
			(stroke
				(width 0.1)
				(type default)
			)
			(layer "B.Fab")
		)
		(fp_line
			(start 0.12065 0.3048)
			(end 0.67945 0.3048)
			(stroke
				(width 0.1)
				(type default)
			)
			(layer "B.Fab")
		)
		(fp_line
			(start -0.120396 0.3048)
			(end -0.120396 0.2794)
			(stroke
				(width 0.1)
				(type default)
			)
			(layer "B.Fab")
		)
		(fp_line
			(start -0.67945 0.3048)
			(end -0.120396 0.3048)
			(stroke
				(width 0.1)
				(type default)
			)
			(layer "B.Fab")
		)
		(pad "1" smd circle
			(at 0.40005 0 270)
			(size 0 0)
			(layers "B.Cu" "B.Mask" "B.Paste")
			(net "U142_VS")
		)
		(pad "2" smd circle
			(at -0.40005 0 270)
			(size 0 0)
			(layers "B.Cu" "B.Mask" "B.Paste")
			(net "GND")
		)
	)
	(footprint ""
		(layer "B.Cu")
		(at 392.961622 -398.455134 180)
		(property "Reference" "C1022"
			(at 0 0 0)
			(layer "B.SilkS")
			(hide yes)
			(effects
				(font
					(size 1.27 1.27)
				)
				(justify mirror)
			)
		)
		(property "Value" ""
			(at 0 0 0)
			(layer "B.Fab")
			(effects
				(font
					(size 1.27 1.27)
				)
				(justify mirror)
			)
		)
		(duplicate_pad_numbers_are_jumpers no)
		(fp_line
			(start 1.524 0.762)
			(end 1.524 -0.762)
			(stroke
				(width 0.1524)
				(type default)
			)
			(layer "B.SilkS")
		)
		(fp_line
			(start 1.524 -0.762)
			(end -1.524 -0.762)
			(stroke
				(width 0.1524)
				(type default)
			)
			(layer "B.SilkS")
		)
		(fp_line
			(start -1.524 0.762)
			(end 1.524 0.762)
			(stroke
				(width 0.1524)
				(type default)
			)
			(layer "B.SilkS")
		)
		(fp_line
			(start -1.524 -0.762)
			(end -1.524 0.762)
			(stroke
				(width 0.1524)
				(type default)
			)
			(layer "B.SilkS")
		)
		(fp_line
			(start 1.1049 0.724916)
			(end -1.1049 0.724916)
			(stroke
				(width 0.1)
				(type default)
			)
			(layer "B.Fab")
		)
		(fp_line
			(start 1.1049 -0.724916)
			(end 1.1049 0.724916)
			(stroke
				(width 0.1)
				(type default)
			)
			(layer "B.Fab")
		)
		(fp_line
			(start -1.1049 0.724916)
			(end -1.1049 -0.724916)
			(stroke
				(width 0.1)
				(type default)
			)
			(layer "B.Fab")
		)
		(fp_line
			(start -1.1049 -0.724916)
			(end 1.1049 -0.724916)
			(stroke
				(width 0.1)
				(type default)
			)
			(layer "B.Fab")
		)
		(pad "1" smd rect
			(at 0.889 0 180)
			(size 1.016 1.27)
			(layers "B.Cu" "B.Mask" "B.Paste")
			(net "P0V9_CPU0_RT3_2A")
		)
		(pad "2" smd rect
			(at -0.889 0 180)
			(size 1.016 1.27)
			(layers "B.Cu" "B.Mask" "B.Paste")
			(net "GND")
		)
	)
	(footprint ""
		(layer "B.Cu")
		(at 94.34322 -180.010562 90)
		(property "Reference" "PR192"
			(at 0 0 90)
			(layer "B.SilkS")
			(hide yes)
			(effects
				(font
					(size 1.27 1.27)
				)
				(justify mirror)
			)
		)
		(property "Value" ""
			(at 0 0 90)
			(layer "B.Fab")
			(effects
				(font
					(size 1.27 1.27)
				)
				(justify mirror)
			)
		)
		(duplicate_pad_numbers_are_jumpers no)
		(fp_line
			(start 0.7874 -0.4064)
			(end -0.7874 -0.4064)
			(stroke
				(width 0.1524)
				(type default)
			)
			(layer "B.SilkS")
		)
		(fp_line
			(start -0.7874 -0.4064)
			(end -0.7874 0.4064)
			(stroke
				(width 0.1524)
				(type default)
			)
			(layer "B.SilkS")
		)
		(fp_line
			(start 0.7874 0.4064)
			(end 0.7874 -0.4064)
			(stroke
				(width 0.1524)
				(type default)
			)
			(layer "B.SilkS")
		)
		(fp_line
			(start -0.7874 0.4064)
			(end 0.7874 0.4064)
			(stroke
				(width 0.1524)
				(type default)
			)
			(layer "B.SilkS")
		)
		(fp_line
			(start 0.67945 -0.305054)
			(end 0.12065 -0.305054)
			(stroke
				(width 0.1)
				(type default)
			)
			(layer "B.Fab")
		)
		(fp_line
			(start 0.12065 -0.305054)
			(end 0.12065 -0.2794)
			(stroke
				(width 0.1)
				(type default)
			)
			(layer "B.Fab")
		)
		(fp_line
			(start -0.12065 -0.3048)
			(end -0.67945 -0.3048)
			(stroke
				(width 0.1)
				(type default)
			)
			(layer "B.Fab")
		)
		(fp_line
			(start -0.67945 -0.3048)
			(end -0.67945 0.3048)
			(stroke
				(width 0.1)
				(type default)
			)
			(layer "B.Fab")
		)
		(fp_line
			(start 0.12065 -0.2794)
			(end -0.12065 -0.2794)
			(stroke
				(width 0.1)
				(type default)
			)
			(layer "B.Fab")
		)
		(fp_line
			(start -0.12065 -0.2794)
			(end -0.12065 -0.3048)
			(stroke
				(width 0.1)
				(type default)
			)
			(layer "B.Fab")
		)
		(fp_line
			(start 0.12065 0.2794)
			(end 0.12065 0.3048)
			(stroke
				(width 0.1)
				(type default)
			)
			(layer "B.Fab")
		)
		(fp_line
			(start -0.120396 0.2794)
			(end 0.12065 0.2794)
			(stroke
				(width 0.1)
				(type default)
			)
			(layer "B.Fab")
		)
		(fp_line
			(start 0.67945 0.3048)
			(end 0.67945 -0.305054)
			(stroke
				(width 0.1)
				(type default)
			)
			(layer "B.Fab")
		)
		(fp_line
			(start 0.12065 0.3048)
			(end 0.67945 0.3048)
			(stroke
				(width 0.1)
				(type default)
			)
			(layer "B.Fab")
		)
		(fp_line
			(start -0.120396 0.3048)
			(end -0.120396 0.2794)
			(stroke
				(width 0.1)
				(type default)
			)
			(layer "B.Fab")
		)
		(fp_line
			(start -0.67945 0.3048)
			(end -0.120396 0.3048)
			(stroke
				(width 0.1)
				(type default)
			)
			(layer "B.Fab")
		)
		(pad "1" smd circle
			(at 0.40005 0 270)
			(size 0 0)
			(layers "B.Cu" "B.Mask" "B.Paste")
			(net "PVDDCR_CPU0_P1_VOS2")
		)
		(pad "2" smd circle
			(at -0.40005 0 270)
			(size 0 0)
			(layers "B.Cu" "B.Mask" "B.Paste")
			(net "PVDDCR_CPU0_P1")
		)
	)
	(footprint ""
		(layer "B.Cu")
		(at 339.93582 -326.363076 -90)
		(property "Reference" "PC140_5"
			(at 0 0 90)
			(layer "B.SilkS")
			(hide yes)
			(effects
				(font
					(size 1.27 1.27)
				)
				(justify mirror)
			)
		)
		(property "Value" ""
			(at 0 0 90)
			(layer "B.Fab")
			(effects
				(font
					(size 1.27 1.27)
				)
				(justify mirror)
			)
		)
		(duplicate_pad_numbers_are_jumpers no)
		(fp_line
			(start -1.524 0.762)
			(end 1.524 0.762)
			(stroke
				(width 0.1524)
				(type default)
			)
			(layer "B.SilkS")
		)
		(fp_line
			(start 1.524 0.762)
			(end 1.524 -0.762)
			(stroke
				(width 0.1524)
				(type default)
			)
			(layer "B.SilkS")
		)
		(fp_line
			(start -1.524 -0.762)
			(end -1.524 0.762)
			(stroke
				(width 0.1524)
				(type default)
			)
			(layer "B.SilkS")
		)
		(fp_line
			(start 1.524 -0.762)
			(end -1.524 -0.762)
			(stroke
				(width 0.1524)
				(type default)
			)
			(layer "B.SilkS")
		)
		(fp_line
			(start -1.1049 0.724916)
			(end -1.1049 -0.724916)
			(stroke
				(width 0.1)
				(type default)
			)
			(layer "B.Fab")
		)
		(fp_line
			(start 1.1049 0.724916)
			(end -1.1049 0.724916)
			(stroke
				(width 0.1)
				(type default)
			)
			(layer "B.Fab")
		)
		(fp_line
			(start -1.1049 -0.724916)
			(end 1.1049 -0.724916)
			(stroke
				(width 0.1)
				(type default)
			)
			(layer "B.Fab")
		)
		(fp_line
			(start 1.1049 -0.724916)
			(end 1.1049 0.724916)
			(stroke
				(width 0.1)
				(type default)
			)
			(layer "B.Fab")
		)
		(pad "1" smd rect
			(at 0.889 0 270)
			(size 1.016 1.27)
			(layers "B.Cu" "B.Mask" "B.Paste")
			(net "PVDDCR_CPU1_P0")
		)
		(pad "2" smd rect
			(at -0.889 0 270)
			(size 1.016 1.27)
			(layers "B.Cu" "B.Mask" "B.Paste")
			(net "GND")
		)
	)
	(footprint ""
		(layer "B.Cu")
		(at 175.075088 -244.085364)
		(property "Reference" "R507"
			(at 0 0 0)
			(layer "B.SilkS")
			(hide yes)
			(effects
				(font
					(size 1.27 1.27)
				)
				(justify mirror)
			)
		)
		(property "Value" ""
			(at 0 0 0)
			(layer "B.Fab")
			(effects
				(font
					(size 1.27 1.27)
				)
				(justify mirror)
			)
		)
		(duplicate_pad_numbers_are_jumpers no)
		(fp_line
			(start -0.7874 -0.4064)
			(end -0.7874 0.4064)
			(stroke
				(width 0.1524)
				(type default)
			)
			(layer "B.SilkS")
		)
		(fp_line
			(start -0.7874 0.4064)
			(end 0.7874 0.4064)
			(stroke
				(width 0.1524)
				(type default)
			)
			(layer "B.SilkS")
		)
		(fp_line
			(start 0.7874 -0.4064)
			(end -0.7874 -0.4064)
			(stroke
				(width 0.1524)
				(type default)
			)
			(layer "B.SilkS")
		)
		(fp_line
			(start 0.7874 0.4064)
			(end 0.7874 -0.4064)
			(stroke
				(width 0.1524)
				(type default)
			)
			(layer "B.SilkS")
		)
		(fp_line
			(start -0.67945 -0.3048)
			(end -0.67945 0.3048)
			(stroke
				(width 0.1)
				(type default)
			)
			(layer "B.Fab")
		)
		(fp_line
			(start -0.67945 0.3048)
			(end -0.120396 0.3048)
			(stroke
				(width 0.1)
				(type default)
			)
			(layer "B.Fab")
		)
		(fp_line
			(start -0.12065 -0.3048)
			(end -0.67945 -0.3048)
			(stroke
				(width 0.1)
				(type default)
			)
			(layer "B.Fab")
		)
		(fp_line
			(start -0.12065 -0.2794)
			(end -0.12065 -0.3048)
			(stroke
				(width 0.1)
				(type default)
			)
			(layer "B.Fab")
		)
		(fp_line
			(start -0.120396 0.2794)
			(end 0.12065 0.2794)
			(stroke
				(width 0.1)
				(type default)
			)
			(layer "B.Fab")
		)
		(fp_line
			(start -0.120396 0.3048)
			(end -0.120396 0.2794)
			(stroke
				(width 0.1)
				(type default)
			)
			(layer "B.Fab")
		)
		(fp_line
			(start 0.12065 -0.305054)
			(end 0.12065 -0.2794)
			(stroke
				(width 0.1)
				(type default)
			)
			(layer "B.Fab")
		)
		(fp_line
			(start 0.12065 -0.2794)
			(end -0.12065 -0.2794)
			(stroke
				(width 0.1)
				(type default)
			)
			(layer "B.Fab")
		)
		(fp_line
			(start 0.12065 0.2794)
			(end 0.12065 0.3048)
			(stroke
				(width 0.1)
				(type default)
			)
			(layer "B.Fab")
		)
		(fp_line
			(start 0.12065 0.3048)
			(end 0.67945 0.3048)
			(stroke
				(width 0.1)
				(type default)
			)
			(layer "B.Fab")
		)
		(fp_line
			(start 0.67945 -0.305054)
			(end 0.12065 -0.305054)
			(stroke
				(width 0.1)
				(type default)
			)
			(layer "B.Fab")
		)
		(fp_line
			(start 0.67945 0.3048)
			(end 0.67945 -0.305054)
			(stroke
				(width 0.1)
				(type default)
			)
			(layer "B.Fab")
		)
		(pad "1" smd circle
			(at 0.40005 0 180)
			(size 0 0)
			(layers "B.Cu" "B.Mask" "B.Paste")
			(net "M_H_CPU1_ALERT_N")
		)
		(pad "2" smd circle
			(at -0.40005 0 180)
			(size 0 0)
			(layers "B.Cu" "B.Mask" "B.Paste")
			(net "M_H_CPU1_ALERT_R_N")
		)
	)
	(footprint ""
		(layer "B.Cu")
		(at 314.489846 -416.899344 90)
		(property "Reference" "C6540"
			(at 0 0 90)
			(layer "B.SilkS")
			(hide yes)
			(effects
				(font
					(size 1.27 1.27)
				)
				(justify mirror)
			)
		)
		(property "Value" ""
			(at 0 0 90)
			(layer "B.Fab")
			(effects
				(font
					(size 1.27 1.27)
				)
				(justify mirror)
			)
		)
		(duplicate_pad_numbers_are_jumpers no)
		(fp_line
			(start 0.299974 -0.150114)
			(end -0.299974 -0.150114)
			(stroke
				(width 0.1)
				(type default)
			)
			(layer "B.Fab")
		)
		(fp_line
			(start -0.299974 -0.150114)
			(end -0.299974 0.150114)
			(stroke
				(width 0.1)
				(type default)
			)
			(layer "B.Fab")
		)
		(fp_line
			(start 0.299974 0.150114)
			(end 0.299974 -0.150114)
			(stroke
				(width 0.1)
				(type default)
			)
			(layer "B.Fab")
		)
		(fp_line
			(start -0.299974 0.150114)
			(end 0.299974 0.150114)
			(stroke
				(width 0.1)
				(type default)
			)
			(layer "B.Fab")
		)
		(pad "1" smd rect
			(at 0.2667 0 270)
			(size 0.3048 0.381)
			(layers "B.Cu" "B.Mask" "B.Paste")
			(net "P5E_CPU0_P1_TX_BUF_C_DN<3>")
		)
		(pad "2" smd rect
			(at -0.2667 0 270)
			(size 0.3048 0.381)
			(layers "B.Cu" "B.Mask" "B.Paste")
			(net "P5E_CPU0_P1_TX_BUF_DN<3>")
		)
	)
)
